(kicad_pcb
	(version 20260206)
	(generator "pcbnew")
	(generator_version "10.0")
	(general
		(thickness 1.6)
		(legacy_teardrops no)
	)
	(paper "A4")
	(title_block
		(title "03242023_DA0F0TMBIJ0_F0T_Motherboard_J_brd_V01_OCP.brd")
		(comment 1 "Grand Teton / footprint 1682 of 6105 (U1), pads 4001-4107 of 4677")
	)
	(layers
		(0 "F.Cu" signal "TOP")
		(4 "In1.Cu" signal "GND")
		(6 "In2.Cu" signal "IN1")
		(8 "In3.Cu" signal "GND1")
		(10 "In4.Cu" signal "IN2")
		(12 "In5.Cu" signal "GND2")
		(14 "In6.Cu" signal "IN3")
		(16 "In7.Cu" signal "GND3")
		(18 "In8.Cu" signal "VCC")
		(20 "In9.Cu" signal "VCC1")
		(22 "In10.Cu" signal "GND4")
		(24 "In11.Cu" signal "IN4")
		(26 "In12.Cu" signal "GND5")
		(28 "In13.Cu" signal "IN5")
		(30 "In14.Cu" signal "GND6")
		(32 "In15.Cu" signal "IN6")
		(34 "In16.Cu" signal "GND7")
		(2 "B.Cu" signal "BOTTOM")
		(9 "F.Adhes" user "F.Adhesive")
		(11 "B.Adhes" user "B.Adhesive")
		(13 "F.Paste" user "Package Geometry/Pastemask Top")
		(15 "B.Paste" user "Package Geometry/Pastemask Bottom")
		(5 "F.SilkS" user "Ref Des/Silkscreen Top")
		(7 "B.SilkS" user "Ref Des/Silkscreen Bottom")
		(1 "F.Mask" user "Board Geometry/Soldermask Top")
		(3 "B.Mask" user "Board Geometry/Soldermask Bottom")
		(17 "Dwgs.User" user "User.Drawings")
		(19 "Cmts.User" user "User.Comments")
		(21 "Eco1.User" user "User.Eco1")
		(23 "Eco2.User" user "User.Eco2")
		(25 "Edge.Cuts" user "Board Geometry/Outline")
		(27 "Margin" user)
		(31 "F.CrtYd" user "Package Geometry/Place Bound Top")
		(29 "B.CrtYd" user "Package Geometry/Place Bound Bottom")
		(35 "F.Fab" user "Ref Des/Assembly Top")
		(33 "B.Fab" user "Ref Des/Assembly Bottom")
	)
	(footprint ""
		(layer "F.Cu")
		(at 111.93018 -251.76988 90)
		(property "Reference" "U1"
			(at -74.913236 41.548812 0)
			(unlocked yes)
			(layer "F.SilkS")
			(effects
				(font
					(size 1.6002 1.1938)
					(thickness 0.1524)
				)
				(justify left)
			)
		)
		(property "Value" ""
			(at 0 0 90)
			(layer "F.Fab")
			(effects
				(font
					(size 1.27 1.27)
				)
			)
		)
		(duplicate_pad_numbers_are_jumpers no)
		(pad "ET38" smd oval
			(at -7.311136 26.964132 270)
			(size 0.381 0.4826)
			(drill
				(offset 0 -0.0508)
			)
			(layers "F.Cu" "F.Mask" "F.Paste")
			(net "GND")
		)
		(pad "ET40" smd oval
			(at -5.68325 26.964132 270)
			(size 0.381 0.4826)
			(drill
				(offset 0 -0.0508)
			)
			(layers "F.Cu" "F.Mask" "F.Paste")
			(net "M_E_CPU1_SB_CS_N<1>")
		)
		(pad "ET42" smd oval
			(at -4.055618 26.964132 270)
			(size 0.381 0.4826)
			(drill
				(offset 0 -0.0508)
			)
			(layers "F.Cu" "F.Mask" "F.Paste")
			(net "M_E_CPU1_SB_CA<5>")
		)
		(pad "ET49" smd oval
			(at 3.241802 27.074114 270)
			(size 0.381 0.4826)
			(drill
				(offset 0 -0.0508)
			)
			(layers "F.Cu" "F.Mask" "F.Paste")
			(net "M_E_CPU1_SA_CA<1>")
		)
		(pad "ET51" smd oval
			(at 4.869434 27.074114 270)
			(size 0.381 0.4826)
			(drill
				(offset 0 -0.0508)
			)
			(layers "F.Cu" "F.Mask" "F.Paste")
			(net "M_E_CPU1_SA_CS_N<1>")
		)
		(pad "ET53" smd oval
			(at 6.49732 27.074114 270)
			(size 0.381 0.4826)
			(drill
				(offset 0 -0.0508)
			)
			(layers "F.Cu" "F.Mask" "F.Paste")
			(net "GND")
		)
		(pad "ET55" smd oval
			(at 8.124952 27.074114 270)
			(size 0.381 0.4826)
			(drill
				(offset 0 -0.0508)
			)
			(layers "F.Cu" "F.Mask" "F.Paste")
			(net "M_E_CPU1_SA_DQS_DN<9>")
		)
		(pad "ET57" smd oval
			(at 9.752838 27.074114 270)
			(size 0.381 0.4826)
			(drill
				(offset 0 -0.0508)
			)
			(layers "F.Cu" "F.Mask" "F.Paste")
			(net "GND")
		)
		(pad "ET59" smd oval
			(at 11.380724 27.074114 270)
			(size 0.381 0.4826)
			(drill
				(offset 0 -0.0508)
			)
			(layers "F.Cu" "F.Mask" "F.Paste")
			(net "GND")
		)
		(pad "ET61" smd oval
			(at 13.008356 27.074114 270)
			(size 0.381 0.4826)
			(drill
				(offset 0 -0.0508)
			)
			(layers "F.Cu" "F.Mask" "F.Paste")
			(net "M_E_CPU1_SA_DQS_DN<8>")
		)
		(pad "F4" smd oval
			(at -34.98342 -24.724868 135)
			(size 0.381 0.4826)
			(drill
				(offset 0 -0.0508)
			)
			(layers "F.Cu" "F.Mask" "F.Paste")
			(net "GND")
		)
		(pad "F6" smd oval
			(at -33.355534 -24.724868 135)
			(size 0.381 0.4826)
			(drill
				(offset 0 -0.0508)
			)
			(layers "F.Cu" "F.Mask" "F.Paste")
			(net "GND")
		)
		(pad "F8" smd circle
			(at -31.727902 -24.724868 270)
			(size 0.4318 0.4318)
			(layers "F.Cu" "F.Mask" "F.Paste")
			(net "M_A_CPU1_SB_DQ<30>")
		)
		(pad "F10" smd circle
			(at -30.100016 -24.724868 270)
			(size 0.4318 0.4318)
			(layers "F.Cu" "F.Mask" "F.Paste")
			(net "M_A_CPU1_SB_DQ<27>")
		)
		(pad "F12" smd circle
			(at -28.472384 -24.724868 270)
			(size 0.4318 0.4318)
			(layers "F.Cu" "F.Mask" "F.Paste")
			(net "GND")
		)
		(pad "F14" smd circle
			(at -26.844498 -24.724868 270)
			(size 0.4318 0.4318)
			(layers "F.Cu" "F.Mask" "F.Paste")
			(net "M_B_CPU1_SB_DQ<31>")
		)
		(pad "F16" smd circle
			(at -25.216612 -24.724868 270)
			(size 0.4318 0.4318)
			(layers "F.Cu" "F.Mask" "F.Paste")
			(net "M_B_CPU1_SB_DQ<27>")
		)
		(pad "F18" smd circle
			(at -23.58898 -24.724868 270)
			(size 0.4318 0.4318)
			(layers "F.Cu" "F.Mask" "F.Paste")
			(net "GND")
		)
		(pad "F20" smd circle
			(at -21.961094 -24.724868 270)
			(size 0.4318 0.4318)
			(layers "F.Cu" "F.Mask" "F.Paste")
			(net "M_A_CPU1_SB_DQ<22>")
		)
		(pad "F22" smd circle
			(at -20.333462 -24.724868 270)
			(size 0.4318 0.4318)
			(layers "F.Cu" "F.Mask" "F.Paste")
			(net "M_A_CPU1_SB_DQ<19>")
		)
		(pad "F24" smd circle
			(at -18.705576 -24.724868 270)
			(size 0.4318 0.4318)
			(layers "F.Cu" "F.Mask" "F.Paste")
			(net "GND")
		)
		(pad "F26" smd circle
			(at -17.07769 -24.724868 270)
			(size 0.4318 0.4318)
			(layers "F.Cu" "F.Mask" "F.Paste")
			(net "M_A_CPU1_SB_DQ<14>")
		)
		(pad "F28" smd circle
			(at -15.450058 -24.724868 270)
			(size 0.4318 0.4318)
			(layers "F.Cu" "F.Mask" "F.Paste")
			(net "M_A_CPU1_SB_DQ<11>")
		)
		(pad "F30" smd circle
			(at -13.822426 -24.724868 270)
			(size 0.4318 0.4318)
			(layers "F.Cu" "F.Mask" "F.Paste")
			(net "GND")
		)
		(pad "F32" smd circle
			(at -12.19454 -24.724868 270)
			(size 0.4318 0.4318)
			(layers "F.Cu" "F.Mask" "F.Paste")
			(net "M_A_CPU1_SB_CB<2>")
		)
		(pad "F34" smd circle
			(at -10.566654 -24.724868 270)
			(size 0.4318 0.4318)
			(layers "F.Cu" "F.Mask" "F.Paste")
			(net "M_A_CPU1_SB_CB<7>")
		)
		(pad "F36" smd circle
			(at -8.939022 -24.724868 270)
			(size 0.4318 0.4318)
			(layers "F.Cu" "F.Mask" "F.Paste")
			(net "GND")
		)
		(pad "F38" smd circle
			(at -7.311136 -24.724868 270)
			(size 0.4318 0.4318)
			(layers "F.Cu" "F.Mask" "F.Paste")
			(net "M_A_CPU1_SB_CS_N<2>")
		)
		(pad "F40" smd circle
			(at -5.68325 -24.724868 270)
			(size 0.4318 0.4318)
			(layers "F.Cu" "F.Mask" "F.Paste")
			(net "M_A_CPU1_SB_CA<5>")
		)
		(pad "F42" smd circle
			(at -4.055618 -24.724868 270)
			(size 0.4318 0.4318)
			(layers "F.Cu" "F.Mask" "F.Paste")
			(net "GND")
		)
		(pad "F44" smd circle
			(at -2.427732 -24.724868 270)
			(size 0.4318 0.4318)
			(layers "F.Cu" "F.Mask" "F.Paste")
			(net "M_A_CPU1_SB_CA<1>")
		)
		(pad "F47" smd circle
			(at 1.613916 -24.614886 270)
			(size 0.4318 0.4318)
			(layers "F.Cu" "F.Mask" "F.Paste")
			(net "PWRGD_DRAMPWRGD_CPU1_CD_LVC1_R")
		)
		(pad "F49" smd circle
			(at 3.241802 -24.614886 270)
			(size 0.4318 0.4318)
			(layers "F.Cu" "F.Mask" "F.Paste")
			(net "GND")
		)
		(pad "F51" smd circle
			(at 4.869434 -24.614886 270)
			(size 0.4318 0.4318)
			(layers "F.Cu" "F.Mask" "F.Paste")
			(net "M_A_CPU1_SA_CA<3>")
		)
		(pad "F53" smd circle
			(at 6.49732 -24.614886 270)
			(size 0.4318 0.4318)
			(layers "F.Cu" "F.Mask" "F.Paste")
			(net "M_A_CPU1_SA_CS_N<3>")
		)
		(pad "F55" smd circle
			(at 8.124952 -24.614886 270)
			(size 0.4318 0.4318)
			(layers "F.Cu" "F.Mask" "F.Paste")
			(net "GND")
		)
		(pad "F57" smd circle
			(at 9.752838 -24.614886 270)
			(size 0.4318 0.4318)
			(layers "F.Cu" "F.Mask" "F.Paste")
			(net "M_A_CPU1_SA_CB<6>")
		)
		(pad "F59" smd circle
			(at 11.380724 -24.614886 270)
			(size 0.4318 0.4318)
			(layers "F.Cu" "F.Mask" "F.Paste")
			(net "M_A_CPU1_SA_CB<3>")
		)
		(pad "F61" smd circle
			(at 13.008356 -24.614886 270)
			(size 0.4318 0.4318)
			(layers "F.Cu" "F.Mask" "F.Paste")
			(net "GND")
		)
		(pad "F63" smd circle
			(at 14.635988 -24.614886 270)
			(size 0.4318 0.4318)
			(layers "F.Cu" "F.Mask" "F.Paste")
			(net "M_A_CPU1_SA_DQ<30>")
		)
		(pad "F65" smd circle
			(at 16.263874 -24.614886 270)
			(size 0.4318 0.4318)
			(layers "F.Cu" "F.Mask" "F.Paste")
			(net "M_A_CPU1_SA_DQ<27>")
		)
		(pad "F67" smd circle
			(at 17.89176 -24.614886 270)
			(size 0.4318 0.4318)
			(layers "F.Cu" "F.Mask" "F.Paste")
			(net "GND")
		)
		(pad "F69" smd circle
			(at 19.519392 -24.614886 270)
			(size 0.4318 0.4318)
			(layers "F.Cu" "F.Mask" "F.Paste")
			(net "M_A_CPU1_SA_DQ<22>")
		)
		(pad "F71" smd circle
			(at 21.147278 -24.614886 270)
			(size 0.4318 0.4318)
			(layers "F.Cu" "F.Mask" "F.Paste")
			(net "M_A_CPU1_SA_DQ<19>")
		)
		(pad "F73" smd circle
			(at 22.77491 -24.614886 270)
			(size 0.4318 0.4318)
			(layers "F.Cu" "F.Mask" "F.Paste")
			(net "GND")
		)
		(pad "F75" smd circle
			(at 24.402796 -24.614886 270)
			(size 0.4318 0.4318)
			(layers "F.Cu" "F.Mask" "F.Paste")
			(net "M_A_CPU1_SA_DQ<7>")
		)
		(pad "F77" smd circle
			(at 26.030682 -24.614886 270)
			(size 0.4318 0.4318)
			(layers "F.Cu" "F.Mask" "F.Paste")
			(net "M_A_CPU1_SA_DQS_DP<5>")
		)
		(pad "F79" smd circle
			(at 27.658314 -24.614886 270)
			(size 0.4318 0.4318)
			(layers "F.Cu" "F.Mask" "F.Paste")
			(net "GND")
		)
		(pad "F81" smd circle
			(at 29.2862 -24.614886 270)
			(size 0.4318 0.4318)
			(layers "F.Cu" "F.Mask" "F.Paste")
			(net "UPI_CPU0_CPU1_P2P2_DN<1>")
		)
		(pad "F83" smd circle
			(at 30.914086 -24.614886 270)
			(size 0.4318 0.4318)
			(layers "F.Cu" "F.Mask" "F.Paste")
			(net "GND")
		)
		(pad "F85" smd circle
			(at 32.541718 -24.614886 270)
			(size 0.4318 0.4318)
			(layers "F.Cu" "F.Mask" "F.Paste")
			(net "UPI_CPU1_CPU0_P2P2_DP<1>")
		)
		(pad "F87" smd oval
			(at 34.169604 -24.614886 45)
			(size 0.381 0.4826)
			(drill
				(offset 0 -0.0508)
			)
			(layers "F.Cu" "F.Mask" "F.Paste")
			(net "UPI_CPU1_CPU0_P2P2_DN<3>")
		)
		(pad "F89" smd oval
			(at 35.797236 -24.614886 45)
			(size 0.381 0.4826)
			(drill
				(offset 0 -0.0508)
			)
			(layers "F.Cu" "F.Mask" "F.Paste")
			(net "GND")
		)
		(pad "G3" smd oval
			(at -35.797236 -24.254714 135)
			(size 0.381 0.4826)
			(drill
				(offset 0 -0.0508)
			)
			(layers "F.Cu" "F.Mask" "F.Paste")
			(net "GND")
		)
		(pad "G5" smd oval
			(at -34.169604 -24.254714 135)
			(size 0.381 0.4826)
			(drill
				(offset 0 -0.0508)
			)
			(layers "F.Cu" "F.Mask" "F.Paste")
			(net "CPU1_RSVD<157>")
		)
		(pad "G7" smd circle
			(at -32.541718 -24.254714 270)
			(size 0.4318 0.4318)
			(layers "F.Cu" "F.Mask" "F.Paste")
			(net "GND")
		)
		(pad "G9" smd circle
			(at -30.914086 -24.254714 270)
			(size 0.4318 0.4318)
			(layers "F.Cu" "F.Mask" "F.Paste")
			(net "M_A_CPU1_SB_DQS_DN<8>")
		)
		(pad "G11" smd circle
			(at -29.2862 -24.254714 270)
			(size 0.4318 0.4318)
			(layers "F.Cu" "F.Mask" "F.Paste")
			(net "GND")
		)
		(pad "G13" smd circle
			(at -27.658314 -24.254714 270)
			(size 0.4318 0.4318)
			(layers "F.Cu" "F.Mask" "F.Paste")
			(net "GND")
		)
		(pad "G15" smd circle
			(at -26.030682 -24.254714 270)
			(size 0.4318 0.4318)
			(layers "F.Cu" "F.Mask" "F.Paste")
			(net "M_B_CPU1_SB_DQS_DP<8>")
		)
		(pad "G17" smd circle
			(at -24.402796 -24.254714 270)
			(size 0.4318 0.4318)
			(layers "F.Cu" "F.Mask" "F.Paste")
			(net "GND")
		)
		(pad "G19" smd circle
			(at -22.77491 -24.254714 270)
			(size 0.4318 0.4318)
			(layers "F.Cu" "F.Mask" "F.Paste")
			(net "GND")
		)
		(pad "G21" smd circle
			(at -21.147278 -24.254714 270)
			(size 0.4318 0.4318)
			(layers "F.Cu" "F.Mask" "F.Paste")
			(net "M_A_CPU1_SB_DQS_DN<7>")
		)
		(pad "G23" smd circle
			(at -19.519392 -24.254714 270)
			(size 0.4318 0.4318)
			(layers "F.Cu" "F.Mask" "F.Paste")
			(net "GND")
		)
		(pad "G25" smd circle
			(at -17.89176 -24.254714 270)
			(size 0.4318 0.4318)
			(layers "F.Cu" "F.Mask" "F.Paste")
			(net "GND")
		)
		(pad "G27" smd circle
			(at -16.263874 -24.254714 270)
			(size 0.4318 0.4318)
			(layers "F.Cu" "F.Mask" "F.Paste")
			(net "M_A_CPU1_SB_DQS_DN<6>")
		)
		(pad "G29" smd circle
			(at -14.635988 -24.254714 270)
			(size 0.4318 0.4318)
			(layers "F.Cu" "F.Mask" "F.Paste")
			(net "GND")
		)
		(pad "G31" smd circle
			(at -13.008356 -24.254714 270)
			(size 0.4318 0.4318)
			(layers "F.Cu" "F.Mask" "F.Paste")
			(net "GND")
		)
		(pad "G33" smd circle
			(at -11.380724 -24.254714 270)
			(size 0.4318 0.4318)
			(layers "F.Cu" "F.Mask" "F.Paste")
			(net "M_A_CPU1_SB_DQS_DN<4>")
		)
		(pad "G35" smd circle
			(at -9.752838 -24.254714 270)
			(size 0.4318 0.4318)
			(layers "F.Cu" "F.Mask" "F.Paste")
			(net "GND")
		)
		(pad "G37" smd circle
			(at -8.124952 -24.254714 270)
			(size 0.4318 0.4318)
			(layers "F.Cu" "F.Mask" "F.Paste")
			(net "GND")
		)
		(pad "G39" smd circle
			(at -6.49732 -24.254714 270)
			(size 0.4318 0.4318)
			(layers "F.Cu" "F.Mask" "F.Paste")
			(net "M_A_CPU1_SB_PAR")
		)
		(pad "G41" smd circle
			(at -4.869434 -24.254714 270)
			(size 0.4318 0.4318)
			(layers "F.Cu" "F.Mask" "F.Paste")
			(net "GND")
		)
		(pad "G43" smd circle
			(at -3.241802 -24.254714 270)
			(size 0.4318 0.4318)
			(layers "F.Cu" "F.Mask" "F.Paste")
			(net "GND")
		)
		(pad "G45" smd circle
			(at -1.613916 -24.254714 270)
			(size 0.4318 0.4318)
			(layers "F.Cu" "F.Mask" "F.Paste")
			(net "M_A_CPU1_CLK_DN<1>")
		)
		(pad "G48" smd circle
			(at 2.427732 -24.144986 270)
			(size 0.4318 0.4318)
			(layers "F.Cu" "F.Mask" "F.Paste")
			(net "GND")
		)
		(pad "G50" smd circle
			(at 4.055618 -24.144986 270)
			(size 0.4318 0.4318)
			(layers "F.Cu" "F.Mask" "F.Paste")
			(net "GND")
		)
		(pad "G52" smd circle
			(at 5.68325 -24.144986 270)
			(size 0.4318 0.4318)
			(layers "F.Cu" "F.Mask" "F.Paste")
			(net "M_A_CPU1_SA_CA<1>")
		)
		(pad "G54" smd circle
			(at 7.311136 -24.144986 270)
			(size 0.4318 0.4318)
			(layers "F.Cu" "F.Mask" "F.Paste")
			(net "GND")
		)
		(pad "G56" smd circle
			(at 8.939022 -24.144986 270)
			(size 0.4318 0.4318)
			(layers "F.Cu" "F.Mask" "F.Paste")
			(net "GND")
		)
		(pad "G58" smd circle
			(at 10.566654 -24.144986 270)
			(size 0.4318 0.4318)
			(layers "F.Cu" "F.Mask" "F.Paste")
			(net "M_A_CPU1_SA_DQS_DN<9>")
		)
		(pad "G60" smd circle
			(at 12.19454 -24.144986 270)
			(size 0.4318 0.4318)
			(layers "F.Cu" "F.Mask" "F.Paste")
			(net "GND")
		)
		(pad "G62" smd circle
			(at 13.822426 -24.144986 270)
			(size 0.4318 0.4318)
			(layers "F.Cu" "F.Mask" "F.Paste")
			(net "GND")
		)
		(pad "G64" smd circle
			(at 15.450058 -24.144986 270)
			(size 0.4318 0.4318)
			(layers "F.Cu" "F.Mask" "F.Paste")
			(net "M_A_CPU1_SA_DQS_DN<8>")
		)
		(pad "G66" smd circle
			(at 17.07769 -24.144986 270)
			(size 0.4318 0.4318)
			(layers "F.Cu" "F.Mask" "F.Paste")
			(net "GND")
		)
		(pad "G68" smd circle
			(at 18.705576 -24.144986 270)
			(size 0.4318 0.4318)
			(layers "F.Cu" "F.Mask" "F.Paste")
			(net "GND")
		)
		(pad "G70" smd circle
			(at 20.333462 -24.144986 270)
			(size 0.4318 0.4318)
			(layers "F.Cu" "F.Mask" "F.Paste")
			(net "M_A_CPU1_SA_DQS_DN<7>")
		)
		(pad "G72" smd circle
			(at 21.961094 -24.144986 270)
			(size 0.4318 0.4318)
			(layers "F.Cu" "F.Mask" "F.Paste")
			(net "GND")
		)
		(pad "G74" smd circle
			(at 23.58898 -24.144986 270)
			(size 0.4318 0.4318)
			(layers "F.Cu" "F.Mask" "F.Paste")
			(net "GND")
		)
		(pad "G76" smd circle
			(at 25.216612 -24.144986 270)
			(size 0.4318 0.4318)
			(layers "F.Cu" "F.Mask" "F.Paste")
			(net "M_A_CPU1_SA_DQ<6>")
		)
		(pad "G78" smd circle
			(at 26.844498 -24.144986 270)
			(size 0.4318 0.4318)
			(layers "F.Cu" "F.Mask" "F.Paste")
			(net "M_A_CPU1_SA_DQ<3>")
		)
		(pad "G80" smd circle
			(at 28.472384 -24.144986 270)
			(size 0.4318 0.4318)
			(layers "F.Cu" "F.Mask" "F.Paste")
			(net "UPI_CPU0_CPU1_P2P2_DP<0>")
		)
		(pad "G82" smd circle
			(at 30.100016 -24.144986 270)
			(size 0.4318 0.4318)
			(layers "F.Cu" "F.Mask" "F.Paste")
			(net "UPI_CPU0_CPU1_P2P2_DN<2>")
		)
		(pad "G84" smd circle
			(at 31.727902 -24.144986 270)
			(size 0.4318 0.4318)
			(layers "F.Cu" "F.Mask" "F.Paste")
			(net "GND")
		)
		(pad "G86" smd circle
			(at 33.355534 -24.144986 270)
			(size 0.4318 0.4318)
			(layers "F.Cu" "F.Mask" "F.Paste")
			(net "UPI_CPU1_CPU0_P2P2_DP<4>")
		)
		(pad "G88" smd oval
			(at 34.98342 -24.144986 45)
			(size 0.381 0.4826)
			(drill
				(offset 0 -0.0508)
			)
			(layers "F.Cu" "F.Mask" "F.Paste")
			(net "GND")
		)
		(pad "G90" smd oval
			(at 36.611306 -24.144986 45)
			(size 0.381 0.4826)
			(drill
				(offset 0 -0.0508)
			)
			(layers "F.Cu" "F.Mask" "F.Paste")
			(net "GND")
		)
		(pad "H2" smd oval
			(at -36.611306 -23.784814 135)
			(size 0.381 0.4826)
			(drill
				(offset 0 -0.0508)
			)
			(layers "F.Cu" "F.Mask" "F.Paste")
			(net "GND")
		)
		(pad "H4" smd oval
			(at -34.98342 -23.784814 135)
			(size 0.381 0.4826)
			(drill
				(offset 0 -0.0508)
			)
			(layers "F.Cu" "F.Mask" "F.Paste")
			(net "GND")
		)
		(pad "H6" smd circle
			(at -33.355534 -23.784814 270)
			(size 0.4318 0.4318)
			(layers "F.Cu" "F.Mask" "F.Paste")
			(net "GND")
		)
		(pad "H8" smd circle
			(at -31.727902 -23.784814 270)
			(size 0.4318 0.4318)
			(layers "F.Cu" "F.Mask" "F.Paste")
			(net "GND")
		)
		(pad "H10" smd circle
			(at -30.100016 -23.784814 270)
			(size 0.4318 0.4318)
			(layers "F.Cu" "F.Mask" "F.Paste")
			(net "GND")
		)
		(pad "H12" smd circle
			(at -28.472384 -23.784814 270)
			(size 0.4318 0.4318)
			(layers "F.Cu" "F.Mask" "F.Paste")
			(net "TP_CPU1_A0_DEBUG_EN")
		)
		(pad "H14" smd circle
			(at -26.844498 -23.784814 270)
			(size 0.4318 0.4318)
			(layers "F.Cu" "F.Mask" "F.Paste")
			(net "GND")
		)
		(pad "H16" smd circle
			(at -25.216612 -23.784814 270)
			(size 0.4318 0.4318)
			(layers "F.Cu" "F.Mask" "F.Paste")
			(net "GND")
		)
		(pad "H18" smd circle
			(at -23.58898 -23.784814 270)
			(size 0.4318 0.4318)
			(layers "F.Cu" "F.Mask" "F.Paste")
			(net "M_B_CPU1_SB_DQS_DN<2>")
		)
		(pad "H20" smd circle
			(at -21.961094 -23.784814 270)
			(size 0.4318 0.4318)
			(layers "F.Cu" "F.Mask" "F.Paste")
			(net "GND")
		)
	)
)
